# T6G (Grand Teton) — schematic netlist excerpt (pin names and nets, part order shuffled) for the footprints in the layout excerpt that follows; sources: Cadence DE-HDL packaged netlist, KiCad conversion of 04192023_DAF0TMB3IC0_F0TG_MB_C_brd_V02_OCP.brd

R488  Q_RES  33 5% CHIP  pkg 0402LF  page 54 : A = CPU1_THERMTRIP_N ; B = CPU1_THERMTRIP_R_N

Y8003  Q_XTAL_4P_13BI_24GND  25MHZ MISC  pkg OSC4_E3FB  page 233
  X1  = CLK_GEN2_XTAL_IN_R
  G1  = GND
  X2  = CLK_GEN2_XTAL_OUT
  G2  = GND

(kicad_pcb
	(version 20260206)
	(generator "pcbnew")
	(generator_version "10.0")
	(general
		(thickness 1.6)
		(legacy_teardrops no)
	)
	(paper "A4")
	(title_block
		(title "04192023_DAF0TMB3IC0_F0TG_MB_C_brd_V02_OCP.brd")
		(comment 1 "Grand Teton / footprints 4662-4663 of 8354")
	)
	(layers
		(0 "F.Cu" signal "TOP")
		(4 "In1.Cu" signal "GND")
		(6 "In2.Cu" signal "IN1")
		(8 "In3.Cu" signal "GND1")
		(10 "In4.Cu" signal "IN2")
		(12 "In5.Cu" signal "GND2")
		(14 "In6.Cu" signal "IN3")
		(16 "In7.Cu" signal "GND3")
		(18 "In8.Cu" signal "VCC")
		(20 "In9.Cu" signal "VCC1")
		(22 "In10.Cu" signal "GND4")
		(24 "In11.Cu" signal "IN4")
		(26 "In12.Cu" signal "GND5")
		(28 "In13.Cu" signal "IN5")
		(30 "In14.Cu" signal "GND6")
		(32 "In15.Cu" signal "IN6")
		(34 "In16.Cu" signal "GND7")
		(2 "B.Cu" signal "BOTTOM")
		(9 "F.Adhes" user "F.Adhesive")
		(11 "B.Adhes" user "B.Adhesive")
		(13 "F.Paste" user "Package Geometry/Pastemask Top")
		(15 "B.Paste" user "Package Geometry/Pastemask Bottom")
		(5 "F.SilkS" user "Ref Des/Silkscreen Top")
		(7 "B.SilkS" user "Ref Des/Silkscreen Bottom")
		(1 "F.Mask" user "Board Geometry/Soldermask Top")
		(3 "B.Mask" user "Board Geometry/Soldermask Bottom")
		(17 "Dwgs.User" user "User.Drawings")
		(19 "Cmts.User" user "User.Comments")
		(21 "Eco1.User" user "User.Eco1")
		(23 "Eco2.User" user "User.Eco2")
		(25 "Edge.Cuts" user "Board Geometry/Outline")
		(27 "Margin" user)
		(31 "F.CrtYd" user "Package Geometry/Place Bound Top")
		(29 "B.CrtYd" user "Package Geometry/Place Bound Bottom")
		(35 "F.Fab" user "Ref Des/Assembly Top")
		(33 "B.Fab" user "Ref Des/Assembly Bottom")
	)
	(footprint ""
		(layer "F.Cu")
		(at 182.9562 -96.103948 90)
		(property "Reference" "R488"
			(at 0 0 90)
			(layer "F.SilkS")
			(hide yes)
			(effects
				(font
					(size 1.27 1.27)
				)
			)
		)
		(property "Value" ""
			(at 0 0 90)
			(layer "F.Fab")
			(effects
				(font
					(size 1.27 1.27)
				)
			)
		)
		(duplicate_pad_numbers_are_jumpers no)
		(fp_line
			(start 0.7874 -0.4064)
			(end 0.7874 0.4064)
			(stroke
				(width 0.1524)
				(type default)
			)
			(layer "F.SilkS")
		)
		(fp_line
			(start -0.7874 -0.4064)
			(end 0.7874 -0.4064)
			(stroke
				(width 0.1524)
				(type default)
			)
			(layer "F.SilkS")
		)
		(fp_line
			(start 0.7874 0.4064)
			(end -0.7874 0.4064)
			(stroke
				(width 0.1524)
				(type default)
			)
			(layer "F.SilkS")
		)
		(fp_line
			(start -0.7874 0.4064)
			(end -0.7874 -0.4064)
			(stroke
				(width 0.1524)
				(type default)
			)
			(layer "F.SilkS")
		)
		(fp_line
			(start -0.12065 -0.305054)
			(end -0.12065 -0.2794)
			(stroke
				(width 0.1)
				(type default)
			)
			(layer "F.Fab")
		)
		(fp_line
			(start -0.67945 -0.305054)
			(end -0.12065 -0.305054)
			(stroke
				(width 0.1)
				(type default)
			)
			(layer "F.Fab")
		)
		(fp_line
			(start 0.67945 -0.3048)
			(end 0.67945 0.3048)
			(stroke
				(width 0.1)
				(type default)
			)
			(layer "F.Fab")
		)
		(fp_line
			(start 0.12065 -0.3048)
			(end 0.67945 -0.3048)
			(stroke
				(width 0.1)
				(type default)
			)
			(layer "F.Fab")
		)
		(fp_line
			(start 0.12065 -0.2794)
			(end 0.12065 -0.3048)
			(stroke
				(width 0.1)
				(type default)
			)
			(layer "F.Fab")
		)
		(fp_line
			(start -0.12065 -0.2794)
			(end 0.12065 -0.2794)
			(stroke
				(width 0.1)
				(type default)
			)
			(layer "F.Fab")
		)
		(fp_line
			(start 0.120396 0.2794)
			(end -0.12065 0.2794)
			(stroke
				(width 0.1)
				(type default)
			)
			(layer "F.Fab")
		)
		(fp_line
			(start -0.12065 0.2794)
			(end -0.12065 0.3048)
			(stroke
				(width 0.1)
				(type default)
			)
			(layer "F.Fab")
		)
		(fp_line
			(start 0.67945 0.3048)
			(end 0.120396 0.3048)
			(stroke
				(width 0.1)
				(type default)
			)
			(layer "F.Fab")
		)
		(fp_line
			(start 0.120396 0.3048)
			(end 0.120396 0.2794)
			(stroke
				(width 0.1)
				(type default)
			)
			(layer "F.Fab")
		)
		(fp_line
			(start -0.12065 0.3048)
			(end -0.67945 0.3048)
			(stroke
				(width 0.1)
				(type default)
			)
			(layer "F.Fab")
		)
		(fp_line
			(start -0.67945 0.3048)
			(end -0.67945 -0.305054)
			(stroke
				(width 0.1)
				(type default)
			)
			(layer "F.Fab")
		)
		(pad "1" smd circle
			(at -0.40005 0 90)
			(size 0 0)
			(layers "F.Cu" "F.Mask" "F.Paste")
			(net "CPU1_THERMTRIP_N")
		)
		(pad "2" smd circle
			(at 0.40005 0 90)
			(size 0 0)
			(layers "F.Cu" "F.Mask" "F.Paste")
			(net "CPU1_THERMTRIP_R_N")
		)
	)
	(footprint ""
		(layer "F.Cu")
		(at 6.029198 -135.388096)
		(property "Reference" "Y8003"
			(at -1.6002 -3.17373 0)
			(unlocked yes)
			(layer "F.SilkS")
			(effects
				(font
					(size 0.7874 0.5842)
					(thickness 0.1524)
				)
				(justify left)
			)
		)
		(property "Value" ""
			(at 0 0 0)
			(layer "F.Fab")
			(effects
				(font
					(size 1.27 1.27)
				)
			)
		)
		(duplicate_pad_numbers_are_jumpers no)
		(fp_line
			(start -1.5367 -1.9558)
			(end 1.5367 -1.9558)
			(stroke
				(width 0.1524)
				(type default)
			)
			(layer "F.SilkS")
		)
		(fp_line
			(start -1.5367 1.9558)
			(end -1.5367 -1.9558)
			(stroke
				(width 0.1524)
				(type default)
			)
			(layer "F.SilkS")
		)
		(fp_line
			(start 1.5367 -1.9558)
			(end 1.5367 1.9558)
			(stroke
				(width 0.1524)
				(type default)
			)
			(layer "F.SilkS")
		)
		(fp_line
			(start 1.5367 1.9558)
			(end -1.5367 1.9558)
			(stroke
				(width 0.1524)
				(type default)
			)
			(layer "F.SilkS")
		)
		(fp_poly
			(pts
				(xy -1.6129 -1.9558) (xy -0.1778 -1.9558) (xy -0.1778 -2.54) (xy -1.6129 -2.54)
			)
			(stroke
				(width 0)
				(type default)
			)
			(fill yes)
			(layer "F.SilkS")
		)
		(fp_line
			(start -1.299972 -1.649984)
			(end 1.299972 -1.649984)
			(stroke
				(width 0.1)
				(type default)
			)
			(layer "F.Fab")
		)
		(fp_line
			(start -1.299972 1.649984)
			(end -1.299972 -1.649984)
			(stroke
				(width 0.1)
				(type default)
			)
			(layer "F.Fab")
		)
		(fp_line
			(start 1.299972 -1.649984)
			(end 1.299972 1.649984)
			(stroke
				(width 0.1)
				(type default)
			)
			(layer "F.Fab")
		)
		(fp_line
			(start 1.299972 1.649984)
			(end -1.299972 1.649984)
			(stroke
				(width 0.1)
				(type default)
			)
			(layer "F.Fab")
		)
		(fp_poly
			(pts
				(xy -1.6129 -1.9558) (xy -0.1778 -1.9558) (xy -0.1778 -2.54) (xy -1.6129 -2.54)
			)
			(stroke
				(width 0)
				(type default)
			)
			(fill yes)
			(layer "F.Fab")
		)
		(pad "1" smd rect
			(at -0.8001 -1.100074)
			(size 1.2192 1.4224)
			(layers "F.Cu" "F.Mask" "F.Paste")
			(net "CLK_GEN2_XTAL_IN_R")
		)
		(pad "2" smd rect
			(at -0.8001 1.100074)
			(size 1.2192 1.4224)
			(layers "F.Cu" "F.Mask" "F.Paste")
			(net "GND")
		)
		(pad "3" smd rect
			(at 0.8001 1.100074)
			(size 1.2192 1.4224)
			(layers "F.Cu" "F.Mask" "F.Paste")
			(net "CLK_GEN2_XTAL_OUT")
		)
		(pad "4" smd rect
			(at 0.8001 -1.100074)
			(size 1.2192 1.4224)
			(layers "F.Cu" "F.Mask" "F.Paste")
			(net "GND")
		)
	)
)
